# BASEBOARD_FAB2 (Tioga Pass) — schematic netlist excerpt (pin names and nets, part order shuffled) for the footprints in the layout excerpt that follows; sources: Cadence DE-HDL packaged netlist, KiCad conversion of Wiwynn_Tioga_Pass_MB.brd

R7W5  RES  0.0 5% CHIP  pkg 0402  page 153 : A = SPI_SWITCH_CS0_N ; B = SPI_CS0_PRIMARY_R_N
C6N3  CAP  10UF 16V 10% X6S  pkg 0805  page 205 : A = VR_FET_SW_P12V_STBY_PVCCIN_CPU0 ; B = GND
R1R12  RES  10.0K 1% CHIP  pkg 0402  page 139 : A = CLK_50M_CKMNG_SPRVLLE ; B = GND

(kicad_pcb
	(version 20260206)
	(generator "pcbnew")
	(generator_version "10.0")
	(general
		(thickness 1.6)
		(legacy_teardrops no)
	)
	(paper "A4")
	(title_block
		(title "Wiwynn_Tioga_Pass_MB.brd")
		(comment 1 "Tioga Pass / footprints 2543-2545 of 4770")
	)
	(layers
		(0 "F.Cu" signal "TOP")
		(4 "In1.Cu" signal "L2GND")
		(6 "In2.Cu" signal "L3")
		(8 "In3.Cu" signal "L4GND")
		(10 "In4.Cu" signal "L5")
		(12 "In5.Cu" signal "L6GND")
		(14 "In6.Cu" signal "L7VCC")
		(16 "In7.Cu" signal "L8VCC")
		(18 "In8.Cu" signal "L9GND")
		(20 "In9.Cu" signal "L10")
		(22 "In10.Cu" signal "L11GND")
		(24 "In11.Cu" signal "L12")
		(26 "In12.Cu" signal "L13GND")
		(2 "B.Cu" signal "BOTTOM")
		(9 "F.Adhes" user "F.Adhesive")
		(11 "B.Adhes" user "B.Adhesive")
		(13 "F.Paste" user "Package Geometry/Pastemask Top")
		(15 "B.Paste" user "Package Geometry/Pastemask Bottom")
		(5 "F.SilkS" user "Ref Des/Silkscreen Top")
		(7 "B.SilkS" user "Ref Des/Silkscreen Bottom")
		(1 "F.Mask" user "Board Geometry/Soldermask Top")
		(3 "B.Mask" user "Board Geometry/Soldermask Bottom")
		(17 "Dwgs.User" user "User.Drawings")
		(19 "Cmts.User" user "User.Comments")
		(21 "Eco1.User" user "User.Eco1")
		(23 "Eco2.User" user "User.Eco2")
		(25 "Edge.Cuts" user "Board Geometry/Outline")
		(27 "Margin" user)
		(31 "F.CrtYd" user "Package Geometry/Place Bound Top")
		(29 "B.CrtYd" user "Package Geometry/Place Bound Bottom")
		(35 "F.Fab" user "Ref Des/Assembly Top")
		(33 "B.Fab" user "Ref Des/Assembly Bottom")
	)
	(footprint ""
		(layer "B.Cu")
		(at 197.866 -98.933 90)
		(property "Reference" "C6N3"
			(at 0 0 90)
			(layer "B.SilkS")
			(hide yes)
			(effects
				(font
					(size 1.27 1.27)
				)
				(justify mirror)
			)
		)
		(property "Value" ""
			(at 0 0 90)
			(layer "B.Fab")
			(effects
				(font
					(size 1.27 1.27)
				)
				(justify mirror)
			)
		)
		(duplicate_pad_numbers_are_jumpers no)
		(fp_rect
			(start 0.7239 1.9939)
			(end -0.7239 -0.2159)
			(stroke
				(width 0)
				(type default)
			)
			(fill no)
			(layer "B.CrtYd")
		)
		(fp_line
			(start 0.7239 -0.2159)
			(end 0.7239 1.9939)
			(stroke
				(width 0.1)
				(type default)
			)
			(layer "B.Fab")
		)
		(fp_line
			(start -0.7239 -0.2159)
			(end 0.7239 -0.2159)
			(stroke
				(width 0.1)
				(type default)
			)
			(layer "B.Fab")
		)
		(fp_line
			(start 0.7239 1.9939)
			(end -0.7239 1.9939)
			(stroke
				(width 0.1)
				(type default)
			)
			(layer "B.Fab")
		)
		(fp_line
			(start -0.7239 1.9939)
			(end -0.7239 -0.2159)
			(stroke
				(width 0.1)
				(type default)
			)
			(layer "B.Fab")
		)
		(pad "1" smd rect
			(at 0 0 270)
			(size 1.27 1.016)
			(layers "B.Cu" "B.Mask" "B.Paste")
			(net "VR_FET_SW_P12V_STBY_PVCCIN_CPU0")
		)
		(pad "2" smd rect
			(at 0 1.778 270)
			(size 1.27 1.016)
			(layers "B.Cu" "B.Mask" "B.Paste")
			(net "GND")
		)
		(zone
			(layer "B.Cu")
			(hatch none 0.5)
			(connect_pads
				(clearance 0)
			)
			(min_thickness 0.25)
			(keepout
				(tracks not_allowed)
				(vias allowed)
				(pads allowed)
				(copperpour not_allowed)
				(footprints allowed)
			)
			(placement
				(enabled no)
				(sheetname "")
			)
			(fill
				(thermal_gap 0.5)
				(thermal_bridge_width 0.5)
				(island_removal_mode 0)
			)
			(polygon
				(pts
					(xy 199.136 -99.568) (xy 198.374 -99.568) (xy 198.374 -98.298) (xy 199.136 -98.298)
				)
			)
		)
	)
	(footprint ""
		(layer "B.Cu")
		(at 394.335 -67.056 90)
		(property "Reference" "R7W5"
			(at 0.8382 -0.67818 90)
			(unlocked yes)
			(layer "B.SilkS")
			(effects
				(font
					(size 0.4064 0.254)
					(thickness 0.1524)
				)
				(justify left mirror)
			)
		)
		(property "Value" ""
			(at 0 0 90)
			(layer "B.Fab")
			(effects
				(font
					(size 1.27 1.27)
				)
				(justify mirror)
			)
		)
		(duplicate_pad_numbers_are_jumpers no)
		(fp_poly
			(pts
				(xy 0.2794 -0.1016) (xy -0.2794 -0.1016) (xy -0.2794 0.9906) (xy 0.2794 0.9906)
			)
			(stroke
				(width 0)
				(type default)
			)
			(fill no)
			(layer "B.CrtYd")
		)
		(fp_line
			(start 0.2794 -0.1016)
			(end 0.2794 0.9906)
			(stroke
				(width 0.1)
				(type default)
			)
			(layer "B.Fab")
		)
		(fp_line
			(start -0.2794 -0.1016)
			(end 0.2794 -0.1016)
			(stroke
				(width 0.1)
				(type default)
			)
			(layer "B.Fab")
		)
		(fp_line
			(start 0.2794 0.9906)
			(end -0.2794 0.9906)
			(stroke
				(width 0.1)
				(type default)
			)
			(layer "B.Fab")
		)
		(fp_line
			(start -0.2794 0.9906)
			(end -0.2794 -0.1016)
			(stroke
				(width 0.1)
				(type default)
			)
			(layer "B.Fab")
		)
		(pad "1" smd rect
			(at 0 0 270)
			(size 0.508 0.508)
			(layers "B.Cu" "B.Mask" "B.Paste")
			(net "SPI_SWITCH_CS0_N")
		)
		(pad "2" smd rect
			(at 0 0.889 270)
			(size 0.508 0.508)
			(layers "B.Cu" "B.Mask" "B.Paste")
			(net "SPI_CS0_PRIMARY_R_N")
		)
		(zone
			(layer "B.Cu")
			(hatch none 0.5)
			(connect_pads
				(clearance 0)
			)
			(min_thickness 0.25)
			(keepout
				(tracks allowed)
				(vias not_allowed)
				(pads allowed)
				(copperpour not_allowed)
				(footprints allowed)
			)
			(placement
				(enabled no)
				(sheetname "")
			)
			(fill
				(thermal_gap 0.5)
				(thermal_bridge_width 0.5)
				(island_removal_mode 0)
			)
			(polygon
				(pts
					(xy 394.589 -67.31) (xy 394.589 -66.802) (xy 394.97 -66.802) (xy 394.97 -67.31)
				)
			)
		)
		(zone
			(layer "B.Cu")
			(hatch none 0.5)
			(connect_pads
				(clearance 0)
			)
			(min_thickness 0.25)
			(keepout
				(tracks not_allowed)
				(vias allowed)
				(pads allowed)
				(copperpour not_allowed)
				(footprints allowed)
			)
			(placement
				(enabled no)
				(sheetname "")
			)
			(fill
				(thermal_gap 0.5)
				(thermal_bridge_width 0.5)
				(island_removal_mode 0)
			)
			(polygon
				(pts
					(xy 394.97 -67.31) (xy 394.97 -66.802) (xy 394.589 -66.802) (xy 394.589 -67.31)
				)
			)
		)
	)
	(footprint ""
		(layer "B.Cu")
		(at 488.3531 -41.4274 -90)
		(property "Reference" "R1R12"
			(at 0 0 90)
			(layer "B.SilkS")
			(hide yes)
			(effects
				(font
					(size 1.27 1.27)
				)
				(justify mirror)
			)
		)
		(property "Value" ""
			(at 0 0 90)
			(layer "B.Fab")
			(effects
				(font
					(size 1.27 1.27)
				)
				(justify mirror)
			)
		)
		(duplicate_pad_numbers_are_jumpers no)
		(fp_poly
			(pts
				(xy 0.2794 -0.1016) (xy -0.2794 -0.1016) (xy -0.2794 0.9906) (xy 0.2794 0.9906)
			)
			(stroke
				(width 0)
				(type default)
			)
			(fill no)
			(layer "B.CrtYd")
		)
		(fp_line
			(start -0.2794 0.9906)
			(end -0.2794 -0.1016)
			(stroke
				(width 0.1)
				(type default)
			)
			(layer "B.Fab")
		)
		(fp_line
			(start 0.2794 0.9906)
			(end -0.2794 0.9906)
			(stroke
				(width 0.1)
				(type default)
			)
			(layer "B.Fab")
		)
		(fp_line
			(start -0.2794 -0.1016)
			(end 0.2794 -0.1016)
			(stroke
				(width 0.1)
				(type default)
			)
			(layer "B.Fab")
		)
		(fp_line
			(start 0.2794 -0.1016)
			(end 0.2794 0.9906)
			(stroke
				(width 0.1)
				(type default)
			)
			(layer "B.Fab")
		)
		(pad "1" smd rect
			(at 0 0 90)
			(size 0.508 0.508)
			(layers "B.Cu" "B.Mask" "B.Paste")
			(net "CLK_50M_CKMNG_SPRVLLE")
		)
		(pad "2" smd rect
			(at 0 0.889 90)
			(size 0.508 0.508)
			(layers "B.Cu" "B.Mask" "B.Paste")
			(net "GND")
		)
		(zone
			(layer "B.Cu")
			(hatch none 0.5)
			(connect_pads
				(clearance 0)
			)
			(min_thickness 0.25)
			(keepout
				(tracks not_allowed)
				(vias allowed)
				(pads allowed)
				(copperpour not_allowed)
				(footprints allowed)
			)
			(placement
				(enabled no)
				(sheetname "")
			)
			(fill
				(thermal_gap 0.5)
				(thermal_bridge_width 0.5)
				(island_removal_mode 0)
			)
			(polygon
				(pts
					(xy 487.7181 -41.1734) (xy 487.7181 -41.6814) (xy 488.0991 -41.6814) (xy 488.0991 -41.1734)
				)
			)
		)
		(zone
			(layer "B.Cu")
			(hatch none 0.5)
			(connect_pads
				(clearance 0)
			)
			(min_thickness 0.25)
			(keepout
				(tracks allowed)
				(vias not_allowed)
				(pads allowed)
				(copperpour not_allowed)
				(footprints allowed)
			)
			(placement
				(enabled no)
				(sheetname "")
			)
			(fill
				(thermal_gap 0.5)
				(thermal_bridge_width 0.5)
				(island_removal_mode 0)
			)
			(polygon
				(pts
					(xy 488.0991 -41.1734) (xy 488.0991 -41.6814) (xy 487.7181 -41.6814) (xy 487.7181 -41.1734)
				)
			)
		)
	)
)
